(kicad_pcb
	(version 20241229)
	(generator "pcbnew")
	(generator_version "9.0")
	(general
		(thickness 1.62)
		(legacy_teardrops no)
	)
	(paper "A3")
	(title_block
		(title "COM Express 7 Baseboard")
		(date "2025-02-04")
		(rev "1.1.2")
		(company "Antmicro Ltd")
		(comment 1 "www.antmicro.com")
		(comment 9 "footprints 671-676 of 802")
	)
	(layers
		(0 "F.Cu" signal)
		(4 "In1.Cu" signal)
		(6 "In2.Cu" signal)
		(8 "In3.Cu" signal)
		(10 "In4.Cu" signal)
		(12 "In5.Cu" signal)
		(14 "In6.Cu" signal)
		(2 "B.Cu" signal)
		(9 "F.Adhes" user "F.Adhesive")
		(11 "B.Adhes" user "B.Adhesive")
		(13 "F.Paste" user)
		(15 "B.Paste" user)
		(5 "F.SilkS" user "F.Silkscreen")
		(7 "B.SilkS" user "B.Silkscreen")
		(1 "F.Mask" user)
		(3 "B.Mask" user)
		(17 "Dwgs.User" user "User.Drawings")
		(19 "Cmts.User" user "User.Comments")
		(21 "Eco1.User" user "User.Eco1")
		(23 "Eco2.User" user "User.Eco2")
		(25 "Edge.Cuts" user)
		(27 "Margin" user)
		(31 "F.CrtYd" user "F.Courtyard")
		(29 "B.CrtYd" user "B.Courtyard")
		(35 "F.Fab" user)
		(33 "B.Fab" user)
	)
	(footprint "antmicro-footprints:R_0402_1005Metric"
		(layer "B.Cu")
		(at 104.28 87.47 90)
		(descr "Resistor SMD 0402")
		(tags "resistor SMD 0402")
		(property "Reference" "R66"
			(at -1.09 -0.48 90)
			(layer "B.SilkS")
			(effects
				(font
					(size 0.7 0.7)
					(thickness 0.15)
				)
				(justify right bottom mirror)
			)
		)
		(property "Value" "R_330R_0402"
			(at -1.011843 -1.772047 90)
			(layer "B.Fab")
			(effects
				(font
					(size 0.7 0.7)
					(thickness 0.15)
				)
				(justify right bottom mirror)
			)
		)
		(property "Datasheet" "https://www.bourns.com/docs/product-datasheets/cr.pdf"
			(at 0 0 90)
			(layer "F.Fab")
			(hide yes)
			(effects
				(font
					(size 1.27 1.27)
					(thickness 0.15)
				)
			)
		)
		(property "Author" "Antmicro"
			(at 191.75 -16.81 0)
			(layer "B.Fab")
			(hide yes)
			(effects
				(font
					(size 1 1)
					(thickness 0.15)
				)
				(justify mirror)
			)
		)
		(property "License" "Apache-2.0"
			(at 191.75 -16.81 0)
			(layer "B.Fab")
			(hide yes)
			(effects
				(font
					(size 1 1)
					(thickness 0.15)
				)
				(justify mirror)
			)
		)
		(property "MPN" "CR0402-FX-3300GLF"
			(at 191.75 -16.81 0)
			(layer "B.Fab")
			(hide yes)
			(effects
				(font
					(size 1 1)
					(thickness 0.15)
				)
				(justify mirror)
			)
		)
		(property "Manufacturer" "Bourns"
			(at 191.75 -16.81 0)
			(layer "B.Fab")
			(hide yes)
			(effects
				(font
					(size 1 1)
					(thickness 0.15)
				)
				(justify mirror)
			)
		)
		(property "Public" "False"
			(at 191.75 -16.81 0)
			(layer "B.Fab")
			(hide yes)
			(effects
				(font
					(size 1 1)
					(thickness 0.15)
				)
				(justify mirror)
			)
		)
		(property "Tolerance" "1%"
			(at 191.75 -16.81 0)
			(layer "B.Fab")
			(hide yes)
			(effects
				(font
					(size 1 1)
					(thickness 0.15)
				)
				(justify mirror)
			)
		)
		(property "Val" "330R"
			(at 191.75 -16.81 0)
			(layer "B.Fab")
			(hide yes)
			(effects
				(font
					(size 1 1)
					(thickness 0.15)
				)
				(justify mirror)
			)
		)
		(sheetname "USB-C console")
		(sheetfile "usb-c_console.kicad_sch")
		(attr smd)
		(fp_rect
			(start -0.925 0.47)
			(end 0.925 -0.47)
			(stroke
				(width 0.05)
				(type default)
			)
			(fill no)
			(layer "B.CrtYd")
		)
		(fp_rect
			(start -0.5 0.25)
			(end 0.5 -0.25)
			(stroke
				(width 0.15)
				(type solid)
			)
			(fill no)
			(layer "B.Fab")
		)
		(pad "1" smd roundrect
			(at -0.48 0 90)
			(size 0.59 0.64)
			(layers "B.Cu" "B.Mask" "B.Paste")
			(roundrect_rratio 0.25)
			(net 54 "/USB-C console/SH")
			(pintype "passive")
			(teardrops
				(best_length_ratio 0.2)
				(max_length 1)
				(best_width_ratio 0.9)
				(max_width 2)
				(curved_edges yes)
				(filter_ratio 0.9)
				(enabled yes)
				(allow_two_segments yes)
				(prefer_zone_connections yes)
			)
		)
		(pad "2" smd roundrect
			(at 0.48 0 90)
			(size 0.59 0.64)
			(layers "B.Cu" "B.Mask" "B.Paste")
			(roundrect_rratio 0.25)
			(net 1 "GND")
			(pintype "passive")
			(teardrops
				(best_length_ratio 0.2)
				(max_length 1)
				(best_width_ratio 0.9)
				(max_width 2)
				(curved_edges yes)
				(filter_ratio 0.9)
				(enabled yes)
				(allow_two_segments yes)
				(prefer_zone_connections yes)
			)
		)
	)
	(footprint "antmicro-footprints:C_0402_1005Metric"
		(layer "B.Cu")
		(at 213.11 129.12 180)
		(descr "Capacitor SMD 0402")
		(tags "capacitor SMD 0402")
		(property "Reference" "C10"
			(at -1.14 -1.34 0)
			(layer "B.SilkS")
			(effects
				(font
					(size 0.7 0.7)
					(thickness 0.15)
				)
				(justify left bottom mirror)
			)
		)
		(property "Value" "C_100n_0402"
			(at -1.022927 -2.155213 0)
			(layer "B.Fab")
			(effects
				(font
					(size 0.7 0.7)
					(thickness 0.15)
				)
				(justify left bottom mirror)
			)
		)
		(property "Datasheet" "https://www.murata.com/products/productdetail?partno=GRM155R61H104KE14%23"
			(at 0 0 180)
			(layer "F.Fab")
			(hide yes)
			(effects
				(font
					(size 1.27 1.27)
					(thickness 0.15)
				)
			)
		)
		(property "Author" "Antmicro"
			(at 426.22 258.24 0)
			(layer "B.Fab")
			(hide yes)
			(effects
				(font
					(size 1 1)
					(thickness 0.15)
				)
				(justify mirror)
			)
		)
		(property "Dielectric" "X5R"
			(at 426.22 258.24 0)
			(layer "B.Fab")
			(hide yes)
			(effects
				(font
					(size 1 1)
					(thickness 0.15)
				)
				(justify mirror)
			)
		)
		(property "License" "Apache-2.0"
			(at 426.22 258.24 0)
			(layer "B.Fab")
			(hide yes)
			(effects
				(font
					(size 1 1)
					(thickness 0.15)
				)
				(justify mirror)
			)
		)
		(property "MPN" "GRM155R61H104KE14D"
			(at 426.22 258.24 0)
			(layer "B.Fab")
			(hide yes)
			(effects
				(font
					(size 1 1)
					(thickness 0.15)
				)
				(justify mirror)
			)
		)
		(property "Manufacturer" "Murata"
			(at 426.22 258.24 0)
			(layer "B.Fab")
			(hide yes)
			(effects
				(font
					(size 1 1)
					(thickness 0.15)
				)
				(justify mirror)
			)
		)
		(property "Public" "False"
			(at 426.22 258.24 0)
			(layer "B.Fab")
			(hide yes)
			(effects
				(font
					(size 1 1)
					(thickness 0.15)
				)
				(justify mirror)
			)
		)
		(property "Val" "100n"
			(at 426.22 258.24 0)
			(layer "B.Fab")
			(hide yes)
			(effects
				(font
					(size 1 1)
					(thickness 0.15)
				)
				(justify mirror)
			)
		)
		(property "Voltage" "50V"
			(at 426.22 258.24 0)
			(layer "B.Fab")
			(hide yes)
			(effects
				(font
					(size 1 1)
					(thickness 0.15)
				)
				(justify mirror)
			)
		)
		(sheetname "PCIe misc")
		(sheetfile "pcie_misc.kicad_sch")
		(attr smd)
		(fp_rect
			(start -0.925 0.47)
			(end 0.925 -0.47)
			(stroke
				(width 0.05)
				(type default)
			)
			(fill no)
			(layer "B.CrtYd")
		)
		(fp_line
			(start 0.504 0.25)
			(end -0.494 0.25)
			(stroke
				(width 0.15)
				(type solid)
			)
			(layer "B.Fab")
		)
		(fp_line
			(start 0.504 -0.248)
			(end 0.504 0.25)
			(stroke
				(width 0.15)
				(type solid)
			)
			(layer "B.Fab")
		)
		(fp_line
			(start -0.494 0.25)
			(end -0.494 -0.248)
			(stroke
				(width 0.15)
				(type solid)
			)
			(layer "B.Fab")
		)
		(fp_line
			(start -0.494 -0.248)
			(end 0.504 -0.248)
			(stroke
				(width 0.15)
				(type solid)
			)
			(layer "B.Fab")
		)
		(pad "1" smd roundrect
			(at -0.48 0 180)
			(size 0.59 0.64)
			(layers "B.Cu" "B.Mask" "B.Paste")
			(roundrect_rratio 0.25)
			(net 1 "GND")
			(pintype "passive")
			(teardrops
				(best_length_ratio 0.2)
				(max_length 1)
				(best_width_ratio 0.9)
				(max_width 2)
				(curved_edges yes)
				(filter_ratio 0.9)
				(enabled yes)
				(allow_two_segments yes)
				(prefer_zone_connections yes)
			)
		)
		(pad "2" smd roundrect
			(at 0.48 0 180)
			(size 0.59 0.64)
			(layers "B.Cu" "B.Mask" "B.Paste")
			(roundrect_rratio 0.25)
			(net 2 "+3V3")
			(pintype "passive")
			(teardrops
				(best_length_ratio 0.2)
				(max_length 1)
				(best_width_ratio 0.9)
				(max_width 2)
				(curved_edges yes)
				(filter_ratio 0.9)
				(enabled yes)
				(allow_two_segments yes)
				(prefer_zone_connections yes)
			)
		)
	)
	(footprint "antmicro-footprints:C_0603_1608Metric"
		(layer "B.Cu")
		(at 136.426 132.089 -90)
		(descr "Capacitor SMD 0603")
		(tags "capacitor 0603")
		(property "Reference" "C182"
			(at -1.529 -1.574 90)
			(layer "B.SilkS")
			(effects
				(font
					(size 0.7 0.7)
					(thickness 0.15)
				)
				(justify left bottom mirror)
			)
		)
		(property "Value" "C_22u_16V_0603"
			(at -1.42757 -1.770288 90)
			(layer "B.Fab")
			(effects
				(font
					(size 0.7 0.7)
					(thickness 0.15)
				)
				(justify left bottom mirror)
			)
		)
		(property "Datasheet" "https://product.samsungsem.com/mlcc/CL10A226MO7JZN.do"
			(at 0 0 270)
			(layer "F.Fab")
			(hide yes)
			(effects
				(font
					(size 1.27 1.27)
					(thickness 0.15)
				)
			)
		)
		(property "Author" "Antmicro"
			(at 4.337 268.515 0)
			(layer "B.Fab")
			(hide yes)
			(effects
				(font
					(size 1 1)
					(thickness 0.15)
				)
				(justify mirror)
			)
		)
		(property "Dielectric" ""
			(at 4.337 268.515 0)
			(layer "B.Fab")
			(hide yes)
			(effects
				(font
					(size 1 1)
					(thickness 0.15)
				)
				(justify mirror)
			)
		)
		(property "License" "Apache-2.0"
			(at 4.337 268.515 0)
			(layer "B.Fab")
			(hide yes)
			(effects
				(font
					(size 1 1)
					(thickness 0.15)
				)
				(justify mirror)
			)
		)
		(property "MPN" "CL10A226MO7JZNC"
			(at 4.337 268.515 0)
			(layer "B.Fab")
			(hide yes)
			(effects
				(font
					(size 1 1)
					(thickness 0.15)
				)
				(justify mirror)
			)
		)
		(property "Manufacturer" "Samsung Electro-Mechanics"
			(at 4.337 268.515 0)
			(layer "B.Fab")
			(hide yes)
			(effects
				(font
					(size 1 1)
					(thickness 0.15)
				)
				(justify mirror)
			)
		)
		(property "Public" "False"
			(at 4.337 268.515 0)
			(layer "B.Fab")
			(hide yes)
			(effects
				(font
					(size 1 1)
					(thickness 0.15)
				)
				(justify mirror)
			)
		)
		(property "Val" "22u"
			(at 4.337 268.515 0)
			(layer "B.Fab")
			(hide yes)
			(effects
				(font
					(size 1 1)
					(thickness 0.15)
				)
				(justify mirror)
			)
		)
		(property "Voltage" "16V"
			(at 4.337 268.515 0)
			(layer "B.Fab")
			(hide yes)
			(effects
				(font
					(size 1 1)
					(thickness 0.15)
				)
				(justify mirror)
			)
		)
		(sheetname "KR to SFI #2")
		(sheetfile "kr_sfi.kicad_sch")
		(attr smd)
		(fp_line
			(start 0.15 0.4)
			(end -0.15 0.4)
			(stroke
				(width 0.15)
				(type solid)
			)
			(layer "B.SilkS")
		)
		(fp_line
			(start 0.15 -0.4)
			(end -0.15 -0.4)
			(stroke
				(width 0.15)
				(type solid)
			)
			(layer "B.SilkS")
		)
		(fp_rect
			(start -1.25 0.65)
			(end 1.25 -0.65)
			(stroke
				(width 0.05)
				(type solid)
			)
			(fill no)
			(layer "B.CrtYd")
		)
		(fp_rect
			(start -0.8 0.4)
			(end 0.8 -0.4)
			(stroke
				(width 0.15)
				(type solid)
			)
			(fill no)
			(layer "B.Fab")
		)
		(pad "1" smd roundrect
			(at -0.7 0 270)
			(size 0.8 1)
			(layers "B.Cu" "B.Mask" "B.Paste")
			(roundrect_rratio 0.2)
			(net 1 "GND")
			(pintype "passive")
			(teardrops
				(best_length_ratio 0.2)
				(max_length 1)
				(best_width_ratio 0.9)
				(max_width 2)
				(curved_edges yes)
				(filter_ratio 0.9)
				(enabled yes)
				(allow_two_segments yes)
				(prefer_zone_connections yes)
			)
		)
		(pad "2" smd roundrect
			(at 0.7 0 270)
			(size 0.8 1)
			(layers "B.Cu" "B.Mask" "B.Paste")
			(roundrect_rratio 0.2)
			(net 74 "+1V0")
			(pintype "passive")
			(teardrops
				(best_length_ratio 0.2)
				(max_length 1)
				(best_width_ratio 0.9)
				(max_width 2)
				(curved_edges yes)
				(filter_ratio 0.9)
				(enabled yes)
				(allow_two_segments yes)
				(prefer_zone_connections yes)
			)
		)
	)
	(footprint "antmicro-footprints:TP_SMD_0.75mm"
		(layer "B.Cu")
		(at 259.95 85.06 180)
		(property "Reference" "TP11"
			(at -3.15 -0.45 0)
			(layer "B.SilkS")
			(effects
				(font
					(size 0.7 0.7)
					(thickness 0.15)
				)
				(justify left bottom mirror)
			)
		)
		(property "Value" "TP_0.75mm_SMD"
			(at 0 -1.2 0)
			(layer "B.Fab")
			(effects
				(font
					(size 0.7 0.7)
					(thickness 0.15)
				)
				(justify left bottom mirror)
			)
		)
		(property "Author" "Antmicro"
			(at 519.9 170.12 0)
			(layer "B.Fab")
			(hide yes)
			(effects
				(font
					(size 1 1)
					(thickness 0.15)
				)
				(justify mirror)
			)
		)
		(property "License" "Apache-2.0"
			(at 519.9 170.12 0)
			(layer "B.Fab")
			(hide yes)
			(effects
				(font
					(size 1 1)
					(thickness 0.15)
				)
				(justify mirror)
			)
		)
		(property "MPN" ""
			(at 519.9 170.12 0)
			(layer "B.Fab")
			(hide yes)
			(effects
				(font
					(size 1 1)
					(thickness 0.15)
				)
				(justify mirror)
			)
		)
		(property "Manufacturer" ""
			(at 519.9 170.12 0)
			(layer "B.Fab")
			(hide yes)
			(effects
				(font
					(size 1 1)
					(thickness 0.15)
				)
				(justify mirror)
			)
		)
		(property "Public" "False"
			(at 519.9 170.12 0)
			(layer "B.Fab")
			(hide yes)
			(effects
				(font
					(size 1 1)
					(thickness 0.15)
				)
				(justify mirror)
			)
		)
		(sheetname "Misc")
		(sheetfile "misc.kicad_sch")
		(attr exclude_from_pos_files exclude_from_bom)
		(fp_circle
			(center 0 0)
			(end 0.475 0)
			(stroke
				(width 0.05)
				(type default)
			)
			(fill no)
			(layer "B.CrtYd")
		)
		(pad "1" smd circle
			(at 0 0 180)
			(size 0.75 0.75)
			(layers "B.Cu" "B.Mask")
			(net 703 "Net-(U24-GPIO3)")
			(pinfunction "1")
			(pintype "passive")
			(teardrops
				(best_length_ratio 0.4)
				(max_length 1)
				(best_width_ratio 0.9)
				(max_width 2)
				(curved_edges yes)
				(filter_ratio 0.9)
				(enabled yes)
				(allow_two_segments yes)
				(prefer_zone_connections yes)
			)
		)
	)
	(footprint "antmicro-footprints:R_0402_1005Metric"
		(layer "B.Cu")
		(at 126.09 140.06)
		(descr "Resistor SMD 0402")
		(tags "resistor SMD 0402")
		(property "Reference" "R289"
			(at -3.64 1.15 0)
			(layer "B.SilkS")
			(effects
				(font
					(size 0.7 0.7)
					(thickness 0.15)
				)
				(justify right bottom mirror)
			)
		)
		(property "Value" "R_10k_0402"
			(at -1.011843 -1.772047 0)
			(layer "B.Fab")
			(effects
				(font
					(size 0.7 0.7)
					(thickness 0.15)
				)
				(justify right bottom mirror)
			)
		)
		(property "Datasheet" "https://www.bourns.com/docs/product-datasheets/cr.pdf"
			(at 0 0 0)
			(layer "F.Fab")
			(hide yes)
			(effects
				(font
					(size 1.27 1.27)
					(thickness 0.15)
				)
			)
		)
		(property "Author" "Antmicro"
			(at 0 0 0)
			(layer "B.Fab")
			(hide yes)
			(effects
				(font
					(size 1 1)
					(thickness 0.15)
				)
				(justify mirror)
			)
		)
		(property "License" "Apache-2.0"
			(at 0 0 0)
			(layer "B.Fab")
			(hide yes)
			(effects
				(font
					(size 1 1)
					(thickness 0.15)
				)
				(justify mirror)
			)
		)
		(property "MPN" "CR0402-FX-1002GLF"
			(at 0 0 0)
			(layer "B.Fab")
			(hide yes)
			(effects
				(font
					(size 1 1)
					(thickness 0.15)
				)
				(justify mirror)
			)
		)
		(property "Manufacturer" "Bourns"
			(at 0 0 0)
			(layer "B.Fab")
			(hide yes)
			(effects
				(font
					(size 1 1)
					(thickness 0.15)
				)
				(justify mirror)
			)
		)
		(property "Public" "False"
			(at 0 0 0)
			(layer "B.Fab")
			(hide yes)
			(effects
				(font
					(size 1 1)
					(thickness 0.15)
				)
				(justify mirror)
			)
		)
		(property "Tolerance" "1%"
			(at 0 0 0)
			(layer "B.Fab")
			(hide yes)
			(effects
				(font
					(size 1 1)
					(thickness 0.15)
				)
				(justify mirror)
			)
		)
		(property "Val" "10k"
			(at 0 0 0)
			(layer "B.Fab")
			(hide yes)
			(effects
				(font
					(size 1 1)
					(thickness 0.15)
				)
				(justify mirror)
			)
		)
		(sheetname "KR to SFI #2")
		(sheetfile "kr_sfi.kicad_sch")
		(attr smd)
		(fp_rect
			(start -0.925 0.47)
			(end 0.925 -0.47)
			(stroke
				(width 0.05)
				(type default)
			)
			(fill no)
			(layer "B.CrtYd")
		)
		(fp_rect
			(start -0.5 0.25)
			(end 0.5 -0.25)
			(stroke
				(width 0.15)
				(type solid)
			)
			(fill no)
			(layer "B.Fab")
		)
		(pad "1" smd roundrect
			(at -0.48 0)
			(size 0.59 0.64)
			(layers "B.Cu" "B.Mask" "B.Paste")
			(roundrect_rratio 0.25)
			(net 1 "GND")
			(pintype "passive")
			(teardrops
				(best_length_ratio 0.2)
				(max_length 1)
				(best_width_ratio 0.9)
				(max_width 2)
				(curved_edges yes)
				(filter_ratio 0.9)
				(enabled yes)
				(allow_two_segments yes)
				(prefer_zone_connections yes)
			)
		)
		(pad "2" smd roundrect
			(at 0.48 0)
			(size 0.59 0.64)
			(layers "B.Cu" "B.Mask" "B.Paste")
			(roundrect_rratio 0.25)
			(net 674 "Net-(U45C-TESTEN)")
			(pintype "passive")
			(teardrops
				(best_length_ratio 0.2)
				(max_length 1)
				(best_width_ratio 0.9)
				(max_width 2)
				(curved_edges yes)
				(filter_ratio 0.9)
				(enabled yes)
				(allow_two_segments yes)
				(prefer_zone_connections yes)
			)
		)
	)
	(footprint "antmicro-footprints:C_0402_1005Metric"
		(layer "B.Cu")
		(at 218.247 130.326)
		(descr "Capacitor SMD 0402")
		(tags "capacitor SMD 0402")
		(property "Reference" "C107"
			(at -1.397 1.334 0)
			(layer "B.SilkS")
			(effects
				(font
					(size 0.7 0.7)
					(thickness 0.15)
				)
				(justify right bottom mirror)
			)
		)
		(property "Value" "C_100n_0402"
			(at -1.022927 -2.155213 0)
			(layer "B.Fab")
			(effects
				(font
					(size 0.7 0.7)
					(thickness 0.15)
				)
				(justify right bottom mirror)
			)
		)
		(property "Datasheet" "https://www.murata.com/products/productdetail?partno=GRM155R61H104KE14%23"
			(at 0 0 0)
			(layer "F.Fab")
			(hide yes)
			(effects
				(font
					(size 1.27 1.27)
					(thickness 0.15)
				)
			)
		)
		(property "Author" "Antmicro"
			(at 0 0 0)
			(layer "B.Fab")
			(hide yes)
			(effects
				(font
					(size 1 1)
					(thickness 0.15)
				)
				(justify mirror)
			)
		)
		(property "Dielectric" "X5R"
			(at 0 0 0)
			(layer "B.Fab")
			(hide yes)
			(effects
				(font
					(size 1 1)
					(thickness 0.15)
				)
				(justify mirror)
			)
		)
		(property "License" "Apache-2.0"
			(at 0 0 0)
			(layer "B.Fab")
			(hide yes)
			(effects
				(font
					(size 1 1)
					(thickness 0.15)
				)
				(justify mirror)
			)
		)
		(property "MPN" "GRM155R61H104KE14D"
			(at 0 0 0)
			(layer "B.Fab")
			(hide yes)
			(effects
				(font
					(size 1 1)
					(thickness 0.15)
				)
				(justify mirror)
			)
		)
		(property "Manufacturer" "Murata"
			(at 0 0 0)
			(layer "B.Fab")
			(hide yes)
			(effects
				(font
					(size 1 1)
					(thickness 0.15)
				)
				(justify mirror)
			)
		)
		(property "Public" "False"
			(at 0 0 0)
			(layer "B.Fab")
			(hide yes)
			(effects
				(font
					(size 1 1)
					(thickness 0.15)
				)
				(justify mirror)
			)
		)
		(property "Val" "100n"
			(at 0 0 0)
			(layer "B.Fab")
			(hide yes)
			(effects
				(font
					(size 1 1)
					(thickness 0.15)
				)
				(justify mirror)
			)
		)
		(property "Voltage" "50V"
			(at 0 0 0)
			(layer "B.Fab")
			(hide yes)
			(effects
				(font
					(size 1 1)
					(thickness 0.15)
				)
				(justify mirror)
			)
		)
		(sheetname "PCIe misc")
		(sheetfile "pcie_misc.kicad_sch")
		(attr smd)
		(fp_rect
			(start -0.925 0.47)
			(end 0.925 -0.47)
			(stroke
				(width 0.05)
				(type default)
			)
			(fill no)
			(layer "B.CrtYd")
		)
		(fp_line
			(start -0.494 -0.248)
			(end 0.504 -0.248)
			(stroke
				(width 0.15)
				(type solid)
			)
			(layer "B.Fab")
		)
		(fp_line
			(start -0.494 0.25)
			(end -0.494 -0.248)
			(stroke
				(width 0.15)
				(type solid)
			)
			(layer "B.Fab")
		)
		(fp_line
			(start 0.504 -0.248)
			(end 0.504 0.25)
			(stroke
				(width 0.15)
				(type solid)
			)
			(layer "B.Fab")
		)
		(fp_line
			(start 0.504 0.25)
			(end -0.494 0.25)
			(stroke
				(width 0.15)
				(type solid)
			)
			(layer "B.Fab")
		)
		(pad "1" smd roundrect
			(at -0.48 0)
			(size 0.59 0.64)
			(layers "B.Cu" "B.Mask" "B.Paste")
			(roundrect_rratio 0.25)
			(net 1 "GND")
			(pintype "passive")
			(teardrops
				(best_length_ratio 0.2)
				(max_length 1)
				(best_width_ratio 0.9)
				(max_width 2)
				(curved_edges yes)
				(filter_ratio 0.9)
				(enabled yes)
				(allow_two_segments yes)
				(prefer_zone_connections yes)
			)
		)
		(pad "2" smd roundrect
			(at 0.48 0)
			(size 0.59 0.64)
			(layers "B.Cu" "B.Mask" "B.Paste")
			(roundrect_rratio 0.25)
			(net 2 "+3V3")
			(pintype "passive")
			(teardrops
				(best_length_ratio 0.2)
				(max_length 1)
				(best_width_ratio 0.9)
				(max_width 2)
				(curved_edges yes)
				(filter_ratio 0.9)
				(enabled yes)
				(allow_two_segments yes)
				(prefer_zone_connections yes)
			)
		)
	)
)
